(kicad_pcb
	(version 20260206)
	(generator "pcbnew")
	(generator_version "10.0")
	(general
		(thickness 1.6)
		(legacy_teardrops no)
	)
	(paper "A4")
	(title_block
		(title "03242023_DA0F0TMBIJ0_F0T_Motherboard_J_brd_V01_OCP.brd")
		(comment 1 "Grand Teton / footprints 900-907 of 6105")
	)
	(layers
		(0 "F.Cu" signal "TOP")
		(4 "In1.Cu" signal "GND")
		(6 "In2.Cu" signal "IN1")
		(8 "In3.Cu" signal "GND1")
		(10 "In4.Cu" signal "IN2")
		(12 "In5.Cu" signal "GND2")
		(14 "In6.Cu" signal "IN3")
		(16 "In7.Cu" signal "GND3")
		(18 "In8.Cu" signal "VCC")
		(20 "In9.Cu" signal "VCC1")
		(22 "In10.Cu" signal "GND4")
		(24 "In11.Cu" signal "IN4")
		(26 "In12.Cu" signal "GND5")
		(28 "In13.Cu" signal "IN5")
		(30 "In14.Cu" signal "GND6")
		(32 "In15.Cu" signal "IN6")
		(34 "In16.Cu" signal "GND7")
		(2 "B.Cu" signal "BOTTOM")
		(9 "F.Adhes" user "F.Adhesive")
		(11 "B.Adhes" user "B.Adhesive")
		(13 "F.Paste" user "Package Geometry/Pastemask Top")
		(15 "B.Paste" user "Package Geometry/Pastemask Bottom")
		(5 "F.SilkS" user "Ref Des/Silkscreen Top")
		(7 "B.SilkS" user "Ref Des/Silkscreen Bottom")
		(1 "F.Mask" user "Board Geometry/Soldermask Top")
		(3 "B.Mask" user "Board Geometry/Soldermask Bottom")
		(17 "Dwgs.User" user "User.Drawings")
		(19 "Cmts.User" user "User.Comments")
		(21 "Eco1.User" user "User.Eco1")
		(23 "Eco2.User" user "User.Eco2")
		(25 "Edge.Cuts" user "Board Geometry/Outline")
		(27 "Margin" user)
		(31 "F.CrtYd" user "Package Geometry/Place Bound Top")
		(29 "B.CrtYd" user "Package Geometry/Place Bound Bottom")
		(35 "F.Fab" user "Ref Des/Assembly Top")
		(33 "B.Fab" user "Ref Des/Assembly Bottom")
	)
	(footprint ""
		(layer "F.Cu")
		(at 297.41622 -419.02761 -90)
		(property "Reference" "R4134"
			(at 0 0 270)
			(layer "F.SilkS")
			(hide yes)
			(effects
				(font
					(size 1.27 1.27)
				)
			)
		)
		(property "Value" ""
			(at 0 0 270)
			(layer "F.Fab")
			(effects
				(font
					(size 1.27 1.27)
				)
			)
		)
		(duplicate_pad_numbers_are_jumpers no)
		(fp_line
			(start -0.7874 0.4064)
			(end -0.7874 -0.4064)
			(stroke
				(width 0.1524)
				(type default)
			)
			(layer "F.SilkS")
		)
		(fp_line
			(start 0.7874 0.4064)
			(end -0.7874 0.4064)
			(stroke
				(width 0.1524)
				(type default)
			)
			(layer "F.SilkS")
		)
		(fp_line
			(start -0.7874 -0.4064)
			(end 0.7874 -0.4064)
			(stroke
				(width 0.1524)
				(type default)
			)
			(layer "F.SilkS")
		)
		(fp_line
			(start 0.7874 -0.4064)
			(end 0.7874 0.4064)
			(stroke
				(width 0.1524)
				(type default)
			)
			(layer "F.SilkS")
		)
		(fp_line
			(start -0.67945 0.3048)
			(end -0.67945 -0.305054)
			(stroke
				(width 0.1)
				(type default)
			)
			(layer "F.Fab")
		)
		(fp_line
			(start -0.12065 0.3048)
			(end -0.67945 0.3048)
			(stroke
				(width 0.1)
				(type default)
			)
			(layer "F.Fab")
		)
		(fp_line
			(start 0.120396 0.3048)
			(end 0.120396 0.2794)
			(stroke
				(width 0.1)
				(type default)
			)
			(layer "F.Fab")
		)
		(fp_line
			(start 0.67945 0.3048)
			(end 0.120396 0.3048)
			(stroke
				(width 0.1)
				(type default)
			)
			(layer "F.Fab")
		)
		(fp_line
			(start -0.12065 0.2794)
			(end -0.12065 0.3048)
			(stroke
				(width 0.1)
				(type default)
			)
			(layer "F.Fab")
		)
		(fp_line
			(start 0.120396 0.2794)
			(end -0.12065 0.2794)
			(stroke
				(width 0.1)
				(type default)
			)
			(layer "F.Fab")
		)
		(fp_line
			(start -0.12065 -0.2794)
			(end 0.12065 -0.2794)
			(stroke
				(width 0.1)
				(type default)
			)
			(layer "F.Fab")
		)
		(fp_line
			(start 0.12065 -0.2794)
			(end 0.12065 -0.3048)
			(stroke
				(width 0.1)
				(type default)
			)
			(layer "F.Fab")
		)
		(fp_line
			(start 0.12065 -0.3048)
			(end 0.67945 -0.3048)
			(stroke
				(width 0.1)
				(type default)
			)
			(layer "F.Fab")
		)
		(fp_line
			(start 0.67945 -0.3048)
			(end 0.67945 0.3048)
			(stroke
				(width 0.1)
				(type default)
			)
			(layer "F.Fab")
		)
		(fp_line
			(start -0.67945 -0.305054)
			(end -0.12065 -0.305054)
			(stroke
				(width 0.1)
				(type default)
			)
			(layer "F.Fab")
		)
		(fp_line
			(start -0.12065 -0.305054)
			(end -0.12065 -0.2794)
			(stroke
				(width 0.1)
				(type default)
			)
			(layer "F.Fab")
		)
		(pad "1" smd circle
			(at -0.40005 0 270)
			(size 0 0)
			(layers "F.Cu" "F.Mask" "F.Paste")
			(net "GPU_3V3IO_RSVD5_FFU")
		)
		(pad "2" smd circle
			(at 0.40005 0 270)
			(size 0 0)
			(layers "F.Cu" "F.Mask" "F.Paste")
			(net "GND")
		)
	)
	(footprint ""
		(layer "F.Cu")
		(at 161.163 -99.786948)
		(property "Reference" "R1754"
			(at 0 0 0)
			(layer "F.SilkS")
			(hide yes)
			(effects
				(font
					(size 1.27 1.27)
				)
			)
		)
		(property "Value" ""
			(at 0 0 0)
			(layer "F.Fab")
			(effects
				(font
					(size 1.27 1.27)
				)
			)
		)
		(duplicate_pad_numbers_are_jumpers no)
		(fp_line
			(start -0.7874 -0.4064)
			(end 0.7874 -0.4064)
			(stroke
				(width 0.1524)
				(type default)
			)
			(layer "F.SilkS")
		)
		(fp_line
			(start -0.7874 0.4064)
			(end -0.7874 -0.4064)
			(stroke
				(width 0.1524)
				(type default)
			)
			(layer "F.SilkS")
		)
		(fp_line
			(start 0.7874 -0.4064)
			(end 0.7874 0.4064)
			(stroke
				(width 0.1524)
				(type default)
			)
			(layer "F.SilkS")
		)
		(fp_line
			(start 0.7874 0.4064)
			(end -0.7874 0.4064)
			(stroke
				(width 0.1524)
				(type default)
			)
			(layer "F.SilkS")
		)
		(fp_line
			(start -0.67945 -0.305054)
			(end -0.12065 -0.305054)
			(stroke
				(width 0.1)
				(type default)
			)
			(layer "F.Fab")
		)
		(fp_line
			(start -0.67945 0.3048)
			(end -0.67945 -0.305054)
			(stroke
				(width 0.1)
				(type default)
			)
			(layer "F.Fab")
		)
		(fp_line
			(start -0.12065 -0.305054)
			(end -0.12065 -0.2794)
			(stroke
				(width 0.1)
				(type default)
			)
			(layer "F.Fab")
		)
		(fp_line
			(start -0.12065 -0.2794)
			(end 0.12065 -0.2794)
			(stroke
				(width 0.1)
				(type default)
			)
			(layer "F.Fab")
		)
		(fp_line
			(start -0.12065 0.2794)
			(end -0.12065 0.3048)
			(stroke
				(width 0.1)
				(type default)
			)
			(layer "F.Fab")
		)
		(fp_line
			(start -0.12065 0.3048)
			(end -0.67945 0.3048)
			(stroke
				(width 0.1)
				(type default)
			)
			(layer "F.Fab")
		)
		(fp_line
			(start 0.120396 0.2794)
			(end -0.12065 0.2794)
			(stroke
				(width 0.1)
				(type default)
			)
			(layer "F.Fab")
		)
		(fp_line
			(start 0.120396 0.3048)
			(end 0.120396 0.2794)
			(stroke
				(width 0.1)
				(type default)
			)
			(layer "F.Fab")
		)
		(fp_line
			(start 0.12065 -0.3048)
			(end 0.67945 -0.3048)
			(stroke
				(width 0.1)
				(type default)
			)
			(layer "F.Fab")
		)
		(fp_line
			(start 0.12065 -0.2794)
			(end 0.12065 -0.3048)
			(stroke
				(width 0.1)
				(type default)
			)
			(layer "F.Fab")
		)
		(fp_line
			(start 0.67945 -0.3048)
			(end 0.67945 0.3048)
			(stroke
				(width 0.1)
				(type default)
			)
			(layer "F.Fab")
		)
		(fp_line
			(start 0.67945 0.3048)
			(end 0.120396 0.3048)
			(stroke
				(width 0.1)
				(type default)
			)
			(layer "F.Fab")
		)
		(pad "1" smd circle
			(at -0.40005 0)
			(size 0 0)
			(layers "F.Cu" "F.Mask" "F.Paste")
			(net "SGPIO_LD_0")
		)
		(pad "2" smd circle
			(at 0.40005 0)
			(size 0 0)
			(layers "F.Cu" "F.Mask" "F.Paste")
			(net "SGPIO_DEBUG_PLD_LD_N")
		)
	)
	(footprint ""
		(layer "F.Cu")
		(at 14.886178 -107.123484 180)
		(property "Reference" "R4482"
			(at 0 0 180)
			(layer "F.SilkS")
			(hide yes)
			(effects
				(font
					(size 1.27 1.27)
				)
			)
		)
		(property "Value" ""
			(at 0 0 180)
			(layer "F.Fab")
			(effects
				(font
					(size 1.27 1.27)
				)
			)
		)
		(duplicate_pad_numbers_are_jumpers no)
		(fp_line
			(start 0.7874 0.4064)
			(end -0.013462 0.4064)
			(stroke
				(width 0.1524)
				(type default)
			)
			(layer "F.SilkS")
		)
		(fp_line
			(start 0.7874 -0.4064)
			(end 0.7874 0.4064)
			(stroke
				(width 0.1524)
				(type default)
			)
			(layer "F.SilkS")
		)
		(fp_line
			(start -0.003302 -0.4064)
			(end 0.7874 -0.4064)
			(stroke
				(width 0.1524)
				(type default)
			)
			(layer "F.SilkS")
		)
		(fp_line
			(start 0.67945 0.3048)
			(end 0.120396 0.3048)
			(stroke
				(width 0.1)
				(type default)
			)
			(layer "F.Fab")
		)
		(fp_line
			(start 0.67945 -0.3048)
			(end 0.67945 0.3048)
			(stroke
				(width 0.1)
				(type default)
			)
			(layer "F.Fab")
		)
		(fp_line
			(start 0.12065 -0.2794)
			(end 0.12065 -0.3048)
			(stroke
				(width 0.1)
				(type default)
			)
			(layer "F.Fab")
		)
		(fp_line
			(start 0.12065 -0.3048)
			(end 0.67945 -0.3048)
			(stroke
				(width 0.1)
				(type default)
			)
			(layer "F.Fab")
		)
		(fp_line
			(start 0.120396 0.3048)
			(end 0.120396 0.2794)
			(stroke
				(width 0.1)
				(type default)
			)
			(layer "F.Fab")
		)
		(fp_line
			(start 0.120396 0.2794)
			(end -0.12065 0.2794)
			(stroke
				(width 0.1)
				(type default)
			)
			(layer "F.Fab")
		)
		(fp_line
			(start -0.12065 0.3048)
			(end -0.67945 0.3048)
			(stroke
				(width 0.1)
				(type default)
			)
			(layer "F.Fab")
		)
		(fp_line
			(start -0.12065 0.2794)
			(end -0.12065 0.3048)
			(stroke
				(width 0.1)
				(type default)
			)
			(layer "F.Fab")
		)
		(fp_line
			(start -0.12065 -0.2794)
			(end 0.12065 -0.2794)
			(stroke
				(width 0.1)
				(type default)
			)
			(layer "F.Fab")
		)
		(fp_line
			(start -0.12065 -0.305054)
			(end -0.12065 -0.2794)
			(stroke
				(width 0.1)
				(type default)
			)
			(layer "F.Fab")
		)
		(fp_line
			(start -0.67945 0.3048)
			(end -0.67945 -0.305054)
			(stroke
				(width 0.1)
				(type default)
			)
			(layer "F.Fab")
		)
		(fp_line
			(start -0.67945 -0.305054)
			(end -0.12065 -0.305054)
			(stroke
				(width 0.1)
				(type default)
			)
			(layer "F.Fab")
		)
		(pad "1" smd circle
			(at -0.40005 0 180)
			(size 0 0)
			(layers "F.Cu" "F.Mask" "F.Paste")
			(net "USB2_HOST_BMC_B_BUF_DP")
		)
		(pad "2" smd circle
			(at 0.40005 0 180)
			(size 0 0)
			(layers "F.Cu" "F.Mask" "F.Paste")
			(net "GND")
		)
	)
	(footprint ""
		(layer "F.Cu")
		(at 488.89793 -467.88705)
		(property "Reference" "U2_DC"
			(at -3.00355 1.898142 0)
			(unlocked yes)
			(layer "F.SilkS")
			(effects
				(font
					(size 0.7874 0.5842)
					(thickness 0.1524)
				)
				(justify left)
			)
		)
		(property "Value" ""
			(at 0 0 0)
			(layer "F.Fab")
			(effects
				(font
					(size 1.27 1.27)
				)
			)
		)
		(duplicate_pad_numbers_are_jumpers no)
		(pad "1" smd circle
			(at 0 0)
			(size 0.762 0.762)
			(layers "F.Cu" "F.Mask" "F.Paste")
			(net "Net_8483")
		)
	)
	(footprint ""
		(layer "F.Cu")
		(at 111.74222 -294.01008 180)
		(property "Reference" "C230"
			(at 0 0 180)
			(layer "F.SilkS")
			(hide yes)
			(effects
				(font
					(size 1.27 1.27)
				)
			)
		)
		(property "Value" ""
			(at 0 0 180)
			(layer "F.Fab")
			(effects
				(font
					(size 1.27 1.27)
				)
			)
		)
		(duplicate_pad_numbers_are_jumpers no)
		(fp_line
			(start 1.524 0.762)
			(end -1.524 0.762)
			(stroke
				(width 0.1524)
				(type default)
			)
			(layer "F.SilkS")
		)
		(fp_line
			(start 1.524 -0.762)
			(end 1.524 0.762)
			(stroke
				(width 0.1524)
				(type default)
			)
			(layer "F.SilkS")
		)
		(fp_line
			(start -1.524 0.762)
			(end -1.524 -0.762)
			(stroke
				(width 0.1524)
				(type default)
			)
			(layer "F.SilkS")
		)
		(fp_line
			(start -1.524 -0.762)
			(end 1.524 -0.762)
			(stroke
				(width 0.1524)
				(type default)
			)
			(layer "F.SilkS")
		)
		(fp_line
			(start 1.1049 0.724916)
			(end 1.1049 -0.724916)
			(stroke
				(width 0.1)
				(type default)
			)
			(layer "F.Fab")
		)
		(fp_line
			(start 1.1049 -0.724916)
			(end -1.1049 -0.724916)
			(stroke
				(width 0.1)
				(type default)
			)
			(layer "F.Fab")
		)
		(fp_line
			(start -1.1049 0.724916)
			(end 1.1049 0.724916)
			(stroke
				(width 0.1)
				(type default)
			)
			(layer "F.Fab")
		)
		(fp_line
			(start -1.1049 -0.724916)
			(end -1.1049 0.724916)
			(stroke
				(width 0.1)
				(type default)
			)
			(layer "F.Fab")
		)
		(pad "1" smd rect
			(at -0.889 0)
			(size 1.016 1.27)
			(layers "F.Cu" "F.Mask" "F.Paste")
			(net "PVCCIN_CPU1")
		)
		(pad "2" smd rect
			(at 0.889 0)
			(size 1.016 1.27)
			(layers "F.Cu" "F.Mask" "F.Paste")
			(net "GND")
		)
	)
	(footprint ""
		(layer "F.Cu")
		(at 215.351614 -99.79152)
		(property "Reference" "U206"
			(at -2.2606 -2.174748 0)
			(unlocked yes)
			(layer "F.SilkS")
			(effects
				(font
					(size 0.7874 0.5842)
					(thickness 0.1524)
				)
				(justify left)
			)
		)
		(property "Value" ""
			(at 0 0 0)
			(layer "F.Fab")
			(effects
				(font
					(size 1.27 1.27)
				)
			)
		)
		(duplicate_pad_numbers_are_jumpers no)
		(fp_line
			(start -2.046478 -1.450086)
			(end -2.046478 1.450086)
			(stroke
				(width 0.1524)
				(type default)
			)
			(layer "F.SilkS")
		)
		(fp_line
			(start -2.046478 1.450086)
			(end 2.046478 1.450086)
			(stroke
				(width 0.1524)
				(type default)
			)
			(layer "F.SilkS")
		)
		(fp_line
			(start -0.484886 -1.450086)
			(end -2.046478 -1.450086)
			(stroke
				(width 0.1524)
				(type default)
			)
			(layer "F.SilkS")
		)
		(fp_line
			(start 0 -0.762)
			(end -0.484886 -1.450086)
			(stroke
				(width 0.1524)
				(type default)
			)
			(layer "F.SilkS")
		)
		(fp_line
			(start 0.484886 -1.450086)
			(end 0 -0.762)
			(stroke
				(width 0.1524)
				(type default)
			)
			(layer "F.SilkS")
		)
		(fp_line
			(start 2.046478 -1.450086)
			(end 0.484886 -1.450086)
			(stroke
				(width 0.1524)
				(type default)
			)
			(layer "F.SilkS")
		)
		(fp_line
			(start 2.046478 1.450086)
			(end 2.046478 -1.450086)
			(stroke
				(width 0.1524)
				(type default)
			)
			(layer "F.SilkS")
		)
		(fp_poly
			(pts
				(xy -3.2512 -0.44196) (xy -3.2512 -1.45796) (xy -2.2352 -0.94996)
			)
			(stroke
				(width 0)
				(type default)
			)
			(fill yes)
			(layer "F.SilkS")
		)
		(fp_line
			(start -0.87503 -1.450086)
			(end -0.87503 1.450086)
			(stroke
				(width 0.1)
				(type default)
			)
			(layer "F.Fab")
		)
		(fp_line
			(start -0.87503 1.450086)
			(end 0.87503 1.450086)
			(stroke
				(width 0.1)
				(type default)
			)
			(layer "F.Fab")
		)
		(fp_line
			(start 0.87503 -1.450086)
			(end -0.87503 -1.450086)
			(stroke
				(width 0.1)
				(type default)
			)
			(layer "F.Fab")
		)
		(fp_line
			(start 0.87503 1.450086)
			(end 0.87503 -1.450086)
			(stroke
				(width 0.1)
				(type default)
			)
			(layer "F.Fab")
		)
		(fp_poly
			(pts
				(xy -3.2512 -0.44196) (xy -3.2512 -1.45796) (xy -2.2352 -0.94996)
			)
			(stroke
				(width 0)
				(type default)
			)
			(fill yes)
			(layer "F.Fab")
		)
		(pad "1" smd rect
			(at -1.309878 -0.94996 90)
			(size 0.635 1.2192)
			(layers "F.Cu" "F.Mask" "F.Paste")
			(net "FM_UV_ADR_TRIGGER_N")
		)
		(pad "2" smd rect
			(at -1.309878 0 90)
			(size 0.635 1.2192)
			(layers "F.Cu" "F.Mask" "F.Paste")
			(net "GND")
		)
		(pad "3" smd rect
			(at -1.309878 0.94996 90)
			(size 0.635 1.2192)
			(layers "F.Cu" "F.Mask" "F.Paste")
			(net "A_P12V_STBY_ADR_TRIGGER")
		)
		(pad "4" smd rect
			(at 1.309878 0.94996 90)
			(size 0.635 1.2192)
			(layers "F.Cu" "F.Mask" "F.Paste")
			(net "A_P12V_STBY_FP_TRIGGER")
		)
		(pad "5" smd rect
			(at 1.309878 0 90)
			(size 0.635 1.2192)
			(layers "F.Cu" "F.Mask" "F.Paste")
			(net "U206_VDD")
		)
		(pad "6" smd rect
			(at 1.309878 -0.94996 90)
			(size 0.635 1.2192)
			(layers "F.Cu" "F.Mask" "F.Paste")
			(net "A_P12V_STBY_FPH_GATE")
		)
	)
	(footprint ""
		(layer "F.Cu")
		(at 46.067472 -392.183112)
		(property "Reference" "R3362"
			(at 0 0 0)
			(layer "F.SilkS")
			(hide yes)
			(effects
				(font
					(size 1.27 1.27)
				)
			)
		)
		(property "Value" ""
			(at 0 0 0)
			(layer "F.Fab")
			(effects
				(font
					(size 1.27 1.27)
				)
			)
		)
		(duplicate_pad_numbers_are_jumpers no)
		(fp_line
			(start -0.7874 -0.4064)
			(end 0.7874 -0.4064)
			(stroke
				(width 0.1524)
				(type default)
			)
			(layer "F.SilkS")
		)
		(fp_line
			(start -0.7874 0.4064)
			(end -0.7874 -0.4064)
			(stroke
				(width 0.1524)
				(type default)
			)
			(layer "F.SilkS")
		)
		(fp_line
			(start 0.7874 -0.4064)
			(end 0.7874 0.4064)
			(stroke
				(width 0.1524)
				(type default)
			)
			(layer "F.SilkS")
		)
		(fp_line
			(start 0.7874 0.4064)
			(end -0.7874 0.4064)
			(stroke
				(width 0.1524)
				(type default)
			)
			(layer "F.SilkS")
		)
		(fp_line
			(start -0.67945 -0.305054)
			(end -0.12065 -0.305054)
			(stroke
				(width 0.1)
				(type default)
			)
			(layer "F.Fab")
		)
		(fp_line
			(start -0.67945 0.3048)
			(end -0.67945 -0.305054)
			(stroke
				(width 0.1)
				(type default)
			)
			(layer "F.Fab")
		)
		(fp_line
			(start -0.12065 -0.305054)
			(end -0.12065 -0.2794)
			(stroke
				(width 0.1)
				(type default)
			)
			(layer "F.Fab")
		)
		(fp_line
			(start -0.12065 -0.2794)
			(end 0.12065 -0.2794)
			(stroke
				(width 0.1)
				(type default)
			)
			(layer "F.Fab")
		)
		(fp_line
			(start -0.12065 0.2794)
			(end -0.12065 0.3048)
			(stroke
				(width 0.1)
				(type default)
			)
			(layer "F.Fab")
		)
		(fp_line
			(start -0.12065 0.3048)
			(end -0.67945 0.3048)
			(stroke
				(width 0.1)
				(type default)
			)
			(layer "F.Fab")
		)
		(fp_line
			(start 0.120396 0.2794)
			(end -0.12065 0.2794)
			(stroke
				(width 0.1)
				(type default)
			)
			(layer "F.Fab")
		)
		(fp_line
			(start 0.120396 0.3048)
			(end 0.120396 0.2794)
			(stroke
				(width 0.1)
				(type default)
			)
			(layer "F.Fab")
		)
		(fp_line
			(start 0.12065 -0.3048)
			(end 0.67945 -0.3048)
			(stroke
				(width 0.1)
				(type default)
			)
			(layer "F.Fab")
		)
		(fp_line
			(start 0.12065 -0.2794)
			(end 0.12065 -0.3048)
			(stroke
				(width 0.1)
				(type default)
			)
			(layer "F.Fab")
		)
		(fp_line
			(start 0.67945 -0.3048)
			(end 0.67945 0.3048)
			(stroke
				(width 0.1)
				(type default)
			)
			(layer "F.Fab")
		)
		(fp_line
			(start 0.67945 0.3048)
			(end 0.120396 0.3048)
			(stroke
				(width 0.1)
				(type default)
			)
			(layer "F.Fab")
		)
		(pad "1" smd circle
			(at -0.40005 0)
			(size 0 0)
			(layers "F.Cu" "F.Mask" "F.Paste")
			(net "PD_P2E_BUF2_ENSMB")
		)
		(pad "2" smd circle
			(at 0.40005 0)
			(size 0 0)
			(layers "F.Cu" "F.Mask" "F.Paste")
			(net "GND")
		)
	)
	(footprint ""
		(layer "F.Cu")
		(at 45.857922 -358.11841)
		(property "Reference" "PC727_P1_4"
			(at 0 0 0)
			(layer "F.SilkS")
			(hide yes)
			(effects
				(font
					(size 1.27 1.27)
				)
			)
		)
		(property "Value" ""
			(at 0 0 0)
			(layer "F.Fab")
			(effects
				(font
					(size 1.27 1.27)
				)
			)
		)
		(duplicate_pad_numbers_are_jumpers no)
		(fp_line
			(start -1.524 -0.762)
			(end 1.524 -0.762)
			(stroke
				(width 0.1524)
				(type default)
			)
			(layer "F.SilkS")
		)
		(fp_line
			(start -1.524 0.762)
			(end -1.524 -0.762)
			(stroke
				(width 0.1524)
				(type default)
			)
			(layer "F.SilkS")
		)
		(fp_line
			(start 1.524 -0.762)
			(end 1.524 0.762)
			(stroke
				(width 0.1524)
				(type default)
			)
			(layer "F.SilkS")
		)
		(fp_line
			(start 1.524 0.762)
			(end -1.524 0.762)
			(stroke
				(width 0.1524)
				(type default)
			)
			(layer "F.SilkS")
		)
		(fp_line
			(start -1.1049 -0.724916)
			(end -1.1049 0.724916)
			(stroke
				(width 0.1)
				(type default)
			)
			(layer "F.Fab")
		)
		(fp_line
			(start -1.1049 0.724916)
			(end 1.1049 0.724916)
			(stroke
				(width 0.1)
				(type default)
			)
			(layer "F.Fab")
		)
		(fp_line
			(start 1.1049 -0.724916)
			(end -1.1049 -0.724916)
			(stroke
				(width 0.1)
				(type default)
			)
			(layer "F.Fab")
		)
		(fp_line
			(start 1.1049 0.724916)
			(end 1.1049 -0.724916)
			(stroke
				(width 0.1)
				(type default)
			)
			(layer "F.Fab")
		)
		(pad "1" smd rect
			(at -0.889 0 180)
			(size 1.016 1.27)
			(layers "F.Cu" "F.Mask" "F.Paste")
			(net "SW_P12V_PVCCFA_EHV_FIVRA_CPU1_L")
		)
		(pad "2" smd rect
			(at 0.889 0 180)
			(size 1.016 1.27)
			(layers "F.Cu" "F.Mask" "F.Paste")
			(net "GND")
		)
	)
)
